(kicad_pcb
	(version 20260206)
	(generator "pcbnew")
	(generator_version "10.0")
	(general
		(thickness 1.6)
		(legacy_teardrops no)
	)
	(paper "A4")
	(title_block
		(title "04192023_DAF0TMB3IC0_F0TG_MB_C_brd_V02_OCP.brd")
		(comment 1 "Grand Teton / footprint 2165 of 8354 (J20), pads 114-226 of 291")
	)
	(layers
		(0 "F.Cu" signal "TOP")
		(4 "In1.Cu" signal "GND")
		(6 "In2.Cu" signal "IN1")
		(8 "In3.Cu" signal "GND1")
		(10 "In4.Cu" signal "IN2")
		(12 "In5.Cu" signal "GND2")
		(14 "In6.Cu" signal "IN3")
		(16 "In7.Cu" signal "GND3")
		(18 "In8.Cu" signal "VCC")
		(20 "In9.Cu" signal "VCC1")
		(22 "In10.Cu" signal "GND4")
		(24 "In11.Cu" signal "IN4")
		(26 "In12.Cu" signal "GND5")
		(28 "In13.Cu" signal "IN5")
		(30 "In14.Cu" signal "GND6")
		(32 "In15.Cu" signal "IN6")
		(34 "In16.Cu" signal "GND7")
		(2 "B.Cu" signal "BOTTOM")
		(9 "F.Adhes" user "F.Adhesive")
		(11 "B.Adhes" user "B.Adhesive")
		(13 "F.Paste" user "Package Geometry/Pastemask Top")
		(15 "B.Paste" user "Package Geometry/Pastemask Bottom")
		(5 "F.SilkS" user "Ref Des/Silkscreen Top")
		(7 "B.SilkS" user "Ref Des/Silkscreen Bottom")
		(1 "F.Mask" user "Board Geometry/Soldermask Top")
		(3 "B.Mask" user "Board Geometry/Soldermask Bottom")
		(17 "Dwgs.User" user "User.Drawings")
		(19 "Cmts.User" user "User.Comments")
		(21 "Eco1.User" user "User.Eco1")
		(23 "Eco2.User" user "User.Eco2")
		(25 "Edge.Cuts" user "Board Geometry/Outline")
		(27 "Margin" user)
		(31 "F.CrtYd" user "Package Geometry/Place Bound Top")
		(29 "B.CrtYd" user "Package Geometry/Place Bound Bottom")
		(35 "F.Fab" user "Ref Des/Assembly Top")
		(33 "B.Fab" user "Ref Des/Assembly Bottom")
	)
	(footprint ""
		(layer "F.Cu")
		(at 444.594234 -255.560068 180)
		(property "Reference" "J20"
			(at 1.631188 -81.796128 0)
			(unlocked yes)
			(layer "F.SilkS")
			(effects
				(font
					(size 0.7874 0.5842)
					(thickness 0.1524)
				)
			)
		)
		(property "Value" ""
			(at 0 0 180)
			(layer "F.Fab")
			(effects
				(font
					(size 1.27 1.27)
				)
			)
		)
		(duplicate_pad_numbers_are_jumpers no)
		(pad "114" smd rect
			(at -2.050034 37.824918 90)
			(size 0.519938 1.4986)
			(layers "F.Cu" "F.Mask" "F.Paste")
			(net "GND")
		)
		(pad "115" smd rect
			(at -2.050034 38.675056 90)
			(size 0.519938 1.4986)
			(layers "F.Cu" "F.Mask" "F.Paste")
			(net "M_K_CPU0_SB_DQS_DP<1>")
		)
		(pad "116" smd rect
			(at -2.050034 39.52494 90)
			(size 0.519938 1.4986)
			(layers "F.Cu" "F.Mask" "F.Paste")
			(net "M_K_CPU0_SB_DQS_DN<1>")
		)
		(pad "117" smd rect
			(at -2.050034 40.375078 90)
			(size 0.519938 1.4986)
			(layers "F.Cu" "F.Mask" "F.Paste")
			(net "GND")
		)
		(pad "118" smd rect
			(at -2.050034 41.224962 90)
			(size 0.519938 1.4986)
			(layers "F.Cu" "F.Mask" "F.Paste")
			(net "M_K_CPU0_SB_DQ<12>")
		)
		(pad "119" smd rect
			(at -2.050034 42.0751 90)
			(size 0.519938 1.4986)
			(layers "F.Cu" "F.Mask" "F.Paste")
			(net "GND")
		)
		(pad "120" smd rect
			(at -2.050034 42.924984 90)
			(size 0.519938 1.4986)
			(layers "F.Cu" "F.Mask" "F.Paste")
			(net "M_K_CPU0_SB_DQ<13>")
		)
		(pad "121" smd rect
			(at -2.050034 43.775122 90)
			(size 0.519938 1.4986)
			(layers "F.Cu" "F.Mask" "F.Paste")
			(net "GND")
		)
		(pad "122" smd rect
			(at -2.050034 44.625006 90)
			(size 0.519938 1.4986)
			(layers "F.Cu" "F.Mask" "F.Paste")
			(net "M_K_CPU0_SB_DQ<16>")
		)
		(pad "123" smd rect
			(at -2.050034 45.47489 90)
			(size 0.519938 1.4986)
			(layers "F.Cu" "F.Mask" "F.Paste")
			(net "GND")
		)
		(pad "124" smd rect
			(at -2.050034 46.325028 90)
			(size 0.519938 1.4986)
			(layers "F.Cu" "F.Mask" "F.Paste")
			(net "M_K_CPU0_SB_DQ<17>")
		)
		(pad "125" smd rect
			(at -2.050034 47.174912 90)
			(size 0.519938 1.4986)
			(layers "F.Cu" "F.Mask" "F.Paste")
			(net "GND")
		)
		(pad "126" smd rect
			(at -2.050034 48.02505 90)
			(size 0.519938 1.4986)
			(layers "F.Cu" "F.Mask" "F.Paste")
			(net "M_K_CPU0_SB_DQS_DP<2>")
		)
		(pad "127" smd rect
			(at -2.050034 48.874934 90)
			(size 0.519938 1.4986)
			(layers "F.Cu" "F.Mask" "F.Paste")
			(net "M_K_CPU0_SB_DQS_DN<2>")
		)
		(pad "128" smd rect
			(at -2.050034 49.725072 90)
			(size 0.519938 1.4986)
			(layers "F.Cu" "F.Mask" "F.Paste")
			(net "GND")
		)
		(pad "129" smd rect
			(at -2.050034 50.574956 90)
			(size 0.519938 1.4986)
			(layers "F.Cu" "F.Mask" "F.Paste")
			(net "M_K_CPU0_SB_DQ<20>")
		)
		(pad "130" smd rect
			(at -2.050034 51.425094 90)
			(size 0.519938 1.4986)
			(layers "F.Cu" "F.Mask" "F.Paste")
			(net "GND")
		)
		(pad "131" smd rect
			(at -2.050034 52.274978 90)
			(size 0.519938 1.4986)
			(layers "F.Cu" "F.Mask" "F.Paste")
			(net "M_K_CPU0_SB_DQ<21>")
		)
		(pad "132" smd rect
			(at -2.050034 53.125116 90)
			(size 0.519938 1.4986)
			(layers "F.Cu" "F.Mask" "F.Paste")
			(net "GND")
		)
		(pad "133" smd rect
			(at -2.050034 53.975 90)
			(size 0.519938 1.4986)
			(layers "F.Cu" "F.Mask" "F.Paste")
			(net "M_K_CPU0_SB_DQ<24>")
		)
		(pad "134" smd rect
			(at -2.050034 54.824884 90)
			(size 0.519938 1.4986)
			(layers "F.Cu" "F.Mask" "F.Paste")
			(net "GND")
		)
		(pad "135" smd rect
			(at -2.050034 55.675022 90)
			(size 0.519938 1.4986)
			(layers "F.Cu" "F.Mask" "F.Paste")
			(net "M_K_CPU0_SB_DQ<25>")
		)
		(pad "136" smd rect
			(at -2.050034 56.524906 90)
			(size 0.519938 1.4986)
			(layers "F.Cu" "F.Mask" "F.Paste")
			(net "GND")
		)
		(pad "137" smd rect
			(at -2.050034 57.375044 90)
			(size 0.519938 1.4986)
			(layers "F.Cu" "F.Mask" "F.Paste")
			(net "M_K_CPU0_SB_DQS_DP<3>")
		)
		(pad "138" smd rect
			(at -2.050034 58.224928 90)
			(size 0.519938 1.4986)
			(layers "F.Cu" "F.Mask" "F.Paste")
			(net "M_K_CPU0_SB_DQS_DN<3>")
		)
		(pad "139" smd rect
			(at -2.050034 59.075066 90)
			(size 0.519938 1.4986)
			(layers "F.Cu" "F.Mask" "F.Paste")
			(net "GND")
		)
		(pad "140" smd rect
			(at -2.050034 59.92495 90)
			(size 0.519938 1.4986)
			(layers "F.Cu" "F.Mask" "F.Paste")
			(net "M_K_CPU0_SB_DQ<28>")
		)
		(pad "141" smd rect
			(at -2.050034 60.775088 90)
			(size 0.519938 1.4986)
			(layers "F.Cu" "F.Mask" "F.Paste")
			(net "GND")
		)
		(pad "142" smd rect
			(at -2.050034 61.624972 90)
			(size 0.519938 1.4986)
			(layers "F.Cu" "F.Mask" "F.Paste")
			(net "M_K_CPU0_SB_DQ<29>")
		)
		(pad "143" smd rect
			(at -2.050034 62.47511 90)
			(size 0.519938 1.4986)
			(layers "F.Cu" "F.Mask" "F.Paste")
			(net "GND")
		)
		(pad "144" smd rect
			(at -2.050034 63.324994 90)
			(size 0.519938 1.4986)
			(layers "F.Cu" "F.Mask" "F.Paste")
			(net "Net_2390")
		)
		(pad "145" smd rect
			(at 2.050034 -63.324994 90)
			(size 0.519938 1.4986)
			(layers "F.Cu" "F.Mask" "F.Paste")
			(net "P12V_MEM_CPU0")
		)
		(pad "146" smd rect
			(at 2.050034 -62.47511 90)
			(size 0.519938 1.4986)
			(layers "F.Cu" "F.Mask" "F.Paste")
			(net "P12V_MEM_CPU0")
		)
		(pad "147" smd rect
			(at 2.050034 -61.624972 90)
			(size 0.519938 1.4986)
			(layers "F.Cu" "F.Mask" "F.Paste")
			(net "PWRGD_CHK_CPU0_DIMM")
		)
		(pad "148" smd rect
			(at 2.050034 -60.775088 90)
			(size 0.519938 1.4986)
			(layers "F.Cu" "F.Mask" "F.Paste")
			(net "PD_CHK_CPU0_DIMM_SAA")
		)
		(pad "149" smd rect
			(at 2.050034 -59.92495 90)
			(size 0.519938 1.4986)
			(layers "F.Cu" "F.Mask" "F.Paste")
			(net "Net_2391")
		)
		(pad "150" smd rect
			(at 2.050034 -59.075066 90)
			(size 0.519938 1.4986)
			(layers "F.Cu" "F.Mask" "F.Paste")
			(net "Net_2392")
		)
		(pad "151" smd rect
			(at 2.050034 -58.224928 90)
			(size 0.519938 1.4986)
			(layers "F.Cu" "F.Mask" "F.Paste")
			(net "GND")
		)
		(pad "152" smd rect
			(at 2.050034 -57.375044 90)
			(size 0.519938 1.4986)
			(layers "F.Cu" "F.Mask" "F.Paste")
			(net "M_K_CPU0_SA_DQ<2>")
		)
		(pad "153" smd rect
			(at 2.050034 -56.524906 90)
			(size 0.519938 1.4986)
			(layers "F.Cu" "F.Mask" "F.Paste")
			(net "GND")
		)
		(pad "154" smd rect
			(at 2.050034 -55.675022 90)
			(size 0.519938 1.4986)
			(layers "F.Cu" "F.Mask" "F.Paste")
			(net "M_K_CPU0_SA_DQ<3>")
		)
		(pad "155" smd rect
			(at 2.050034 -54.824884 90)
			(size 0.519938 1.4986)
			(layers "F.Cu" "F.Mask" "F.Paste")
			(net "GND")
		)
		(pad "156" smd rect
			(at 2.050034 -53.975 90)
			(size 0.519938 1.4986)
			(layers "F.Cu" "F.Mask" "F.Paste")
			(net "M_K_CPU0_SA_DQS_DN<5>")
		)
		(pad "157" smd rect
			(at 2.050034 -53.125116 90)
			(size 0.519938 1.4986)
			(layers "F.Cu" "F.Mask" "F.Paste")
			(net "M_K_CPU0_SA_DQS_DP<5>")
		)
		(pad "158" smd rect
			(at 2.050034 -52.274978 90)
			(size 0.519938 1.4986)
			(layers "F.Cu" "F.Mask" "F.Paste")
			(net "GND")
		)
		(pad "159" smd rect
			(at 2.050034 -51.425094 90)
			(size 0.519938 1.4986)
			(layers "F.Cu" "F.Mask" "F.Paste")
			(net "M_K_CPU0_SA_DQ<6>")
		)
		(pad "160" smd rect
			(at 2.050034 -50.574956 90)
			(size 0.519938 1.4986)
			(layers "F.Cu" "F.Mask" "F.Paste")
			(net "GND")
		)
		(pad "161" smd rect
			(at 2.050034 -49.725072 90)
			(size 0.519938 1.4986)
			(layers "F.Cu" "F.Mask" "F.Paste")
			(net "M_K_CPU0_SA_DQ<7>")
		)
		(pad "162" smd rect
			(at 2.050034 -48.874934 90)
			(size 0.519938 1.4986)
			(layers "F.Cu" "F.Mask" "F.Paste")
			(net "GND")
		)
		(pad "163" smd rect
			(at 2.050034 -48.02505 90)
			(size 0.519938 1.4986)
			(layers "F.Cu" "F.Mask" "F.Paste")
			(net "M_K_CPU0_SA_DQ<10>")
		)
		(pad "164" smd rect
			(at 2.050034 -47.174912 90)
			(size 0.519938 1.4986)
			(layers "F.Cu" "F.Mask" "F.Paste")
			(net "GND")
		)
		(pad "165" smd rect
			(at 2.050034 -46.325028 90)
			(size 0.519938 1.4986)
			(layers "F.Cu" "F.Mask" "F.Paste")
			(net "M_K_CPU0_SA_DQ<11>")
		)
		(pad "166" smd rect
			(at 2.050034 -45.47489 90)
			(size 0.519938 1.4986)
			(layers "F.Cu" "F.Mask" "F.Paste")
			(net "GND")
		)
		(pad "167" smd rect
			(at 2.050034 -44.625006 90)
			(size 0.519938 1.4986)
			(layers "F.Cu" "F.Mask" "F.Paste")
			(net "M_K_CPU0_SA_DQS_DN<6>")
		)
		(pad "168" smd rect
			(at 2.050034 -43.775122 90)
			(size 0.519938 1.4986)
			(layers "F.Cu" "F.Mask" "F.Paste")
			(net "M_K_CPU0_SA_DQS_DP<6>")
		)
		(pad "169" smd rect
			(at 2.050034 -42.924984 90)
			(size 0.519938 1.4986)
			(layers "F.Cu" "F.Mask" "F.Paste")
			(net "GND")
		)
		(pad "170" smd rect
			(at 2.050034 -42.0751 90)
			(size 0.519938 1.4986)
			(layers "F.Cu" "F.Mask" "F.Paste")
			(net "M_K_CPU0_SA_DQ<14>")
		)
		(pad "171" smd rect
			(at 2.050034 -41.224962 90)
			(size 0.519938 1.4986)
			(layers "F.Cu" "F.Mask" "F.Paste")
			(net "GND")
		)
		(pad "172" smd rect
			(at 2.050034 -40.375078 90)
			(size 0.519938 1.4986)
			(layers "F.Cu" "F.Mask" "F.Paste")
			(net "M_K_CPU0_SA_DQ<15>")
		)
		(pad "173" smd rect
			(at 2.050034 -39.52494 90)
			(size 0.519938 1.4986)
			(layers "F.Cu" "F.Mask" "F.Paste")
			(net "GND")
		)
		(pad "174" smd rect
			(at 2.050034 -38.675056 90)
			(size 0.519938 1.4986)
			(layers "F.Cu" "F.Mask" "F.Paste")
			(net "M_K_CPU0_SA_DQ<18>")
		)
		(pad "175" smd rect
			(at 2.050034 -37.824918 90)
			(size 0.519938 1.4986)
			(layers "F.Cu" "F.Mask" "F.Paste")
			(net "GND")
		)
		(pad "176" smd rect
			(at 2.050034 -36.975034 90)
			(size 0.519938 1.4986)
			(layers "F.Cu" "F.Mask" "F.Paste")
			(net "M_K_CPU0_SA_DQ<19>")
		)
		(pad "177" smd rect
			(at 2.050034 -36.124896 90)
			(size 0.519938 1.4986)
			(layers "F.Cu" "F.Mask" "F.Paste")
			(net "GND")
		)
		(pad "178" smd rect
			(at 2.050034 -35.275012 90)
			(size 0.519938 1.4986)
			(layers "F.Cu" "F.Mask" "F.Paste")
			(net "M_K_CPU0_SA_DQS_DN<7>")
		)
		(pad "179" smd rect
			(at 2.050034 -34.425128 90)
			(size 0.519938 1.4986)
			(layers "F.Cu" "F.Mask" "F.Paste")
			(net "M_K_CPU0_SA_DQS_DP<7>")
		)
		(pad "180" smd rect
			(at 2.050034 -33.57499 90)
			(size 0.519938 1.4986)
			(layers "F.Cu" "F.Mask" "F.Paste")
			(net "GND")
		)
		(pad "181" smd rect
			(at 2.050034 -32.725106 90)
			(size 0.519938 1.4986)
			(layers "F.Cu" "F.Mask" "F.Paste")
			(net "M_K_CPU0_SA_DQ<22>")
		)
		(pad "182" smd rect
			(at 2.050034 -31.874968 90)
			(size 0.519938 1.4986)
			(layers "F.Cu" "F.Mask" "F.Paste")
			(net "GND")
		)
		(pad "183" smd rect
			(at 2.050034 -31.025084 90)
			(size 0.519938 1.4986)
			(layers "F.Cu" "F.Mask" "F.Paste")
			(net "M_K_CPU0_SA_DQ<23>")
		)
		(pad "184" smd rect
			(at 2.050034 -30.174946 90)
			(size 0.519938 1.4986)
			(layers "F.Cu" "F.Mask" "F.Paste")
			(net "GND")
		)
		(pad "185" smd rect
			(at 2.050034 -29.325062 90)
			(size 0.519938 1.4986)
			(layers "F.Cu" "F.Mask" "F.Paste")
			(net "M_K_CPU0_SA_DQ<26>")
		)
		(pad "186" smd rect
			(at 2.050034 -28.474924 90)
			(size 0.519938 1.4986)
			(layers "F.Cu" "F.Mask" "F.Paste")
			(net "GND")
		)
		(pad "187" smd rect
			(at 2.050034 -27.62504 90)
			(size 0.519938 1.4986)
			(layers "F.Cu" "F.Mask" "F.Paste")
			(net "M_K_CPU0_SA_DQ<27>")
		)
		(pad "188" smd rect
			(at 2.050034 -26.774902 90)
			(size 0.519938 1.4986)
			(layers "F.Cu" "F.Mask" "F.Paste")
			(net "GND")
		)
		(pad "189" smd rect
			(at 2.050034 -25.925018 90)
			(size 0.519938 1.4986)
			(layers "F.Cu" "F.Mask" "F.Paste")
			(net "M_K_CPU0_SA_DQS_DN<8>")
		)
		(pad "190" smd rect
			(at 2.050034 -25.07488 90)
			(size 0.519938 1.4986)
			(layers "F.Cu" "F.Mask" "F.Paste")
			(net "M_K_CPU0_SA_DQS_DP<8>")
		)
		(pad "191" smd rect
			(at 2.050034 -24.224996 90)
			(size 0.519938 1.4986)
			(layers "F.Cu" "F.Mask" "F.Paste")
			(net "GND")
		)
		(pad "192" smd rect
			(at 2.050034 -23.375112 90)
			(size 0.519938 1.4986)
			(layers "F.Cu" "F.Mask" "F.Paste")
			(net "M_K_CPU0_SA_DQ<30>")
		)
		(pad "193" smd rect
			(at 2.050034 -22.524974 90)
			(size 0.519938 1.4986)
			(layers "F.Cu" "F.Mask" "F.Paste")
			(net "GND")
		)
		(pad "194" smd rect
			(at 2.050034 -21.67509 90)
			(size 0.519938 1.4986)
			(layers "F.Cu" "F.Mask" "F.Paste")
			(net "M_K_CPU0_SA_DQ<31>")
		)
		(pad "195" smd rect
			(at 2.050034 -20.824952 90)
			(size 0.519938 1.4986)
			(layers "F.Cu" "F.Mask" "F.Paste")
			(net "GND")
		)
		(pad "196" smd rect
			(at 2.050034 -19.975068 90)
			(size 0.519938 1.4986)
			(layers "F.Cu" "F.Mask" "F.Paste")
			(net "M_K_CPU0_SA_CB<2>")
		)
		(pad "197" smd rect
			(at 2.050034 -19.12493 90)
			(size 0.519938 1.4986)
			(layers "F.Cu" "F.Mask" "F.Paste")
			(net "GND")
		)
		(pad "198" smd rect
			(at 2.050034 -18.275046 90)
			(size 0.519938 1.4986)
			(layers "F.Cu" "F.Mask" "F.Paste")
			(net "M_K_CPU0_SA_CB<3>")
		)
		(pad "199" smd rect
			(at 2.050034 -17.424908 90)
			(size 0.519938 1.4986)
			(layers "F.Cu" "F.Mask" "F.Paste")
			(net "GND")
		)
		(pad "200" smd rect
			(at 2.050034 -16.575024 90)
			(size 0.519938 1.4986)
			(layers "F.Cu" "F.Mask" "F.Paste")
			(net "M_K_CPU0_SA_DQS_DN<9>")
		)
		(pad "201" smd rect
			(at 2.050034 -15.724886 90)
			(size 0.519938 1.4986)
			(layers "F.Cu" "F.Mask" "F.Paste")
			(net "M_K_CPU0_SA_DQS_DP<9>")
		)
		(pad "202" smd rect
			(at 2.050034 -14.875002 90)
			(size 0.519938 1.4986)
			(layers "F.Cu" "F.Mask" "F.Paste")
			(net "GND")
		)
		(pad "203" smd rect
			(at 2.050034 -14.025118 90)
			(size 0.519938 1.4986)
			(layers "F.Cu" "F.Mask" "F.Paste")
			(net "M_K_CPU0_SA_CB<6>")
		)
		(pad "204" smd rect
			(at 2.050034 -13.17498 90)
			(size 0.519938 1.4986)
			(layers "F.Cu" "F.Mask" "F.Paste")
			(net "GND")
		)
		(pad "205" smd rect
			(at 2.050034 -12.325096 90)
			(size 0.519938 1.4986)
			(layers "F.Cu" "F.Mask" "F.Paste")
			(net "M_K_CPU0_SA_CB<7>")
		)
		(pad "206" smd rect
			(at 2.050034 -11.474958 90)
			(size 0.519938 1.4986)
			(layers "F.Cu" "F.Mask" "F.Paste")
			(net "GND")
		)
		(pad "207" smd rect
			(at 2.050034 -10.625074 90)
			(size 0.519938 1.4986)
			(layers "F.Cu" "F.Mask" "F.Paste")
			(net "M_K_CPU0_RESET_N")
		)
		(pad "208" smd rect
			(at 2.050034 -9.774936 90)
			(size 0.519938 1.4986)
			(layers "F.Cu" "F.Mask" "F.Paste")
			(net "GND")
		)
		(pad "209" smd rect
			(at 2.050034 -8.925052 90)
			(size 0.519938 1.4986)
			(layers "F.Cu" "F.Mask" "F.Paste")
			(net "M_K_CPU0_SA_CS_N<1>")
		)
		(pad "210" smd rect
			(at 2.050034 -8.074914 90)
			(size 0.519938 1.4986)
			(layers "F.Cu" "F.Mask" "F.Paste")
			(net "GND")
		)
		(pad "211" smd rect
			(at 2.050034 -7.22503 90)
			(size 0.519938 1.4986)
			(layers "F.Cu" "F.Mask" "F.Paste")
			(net "M_K_CPU0_SA_CA<1>")
		)
		(pad "212" smd rect
			(at 2.050034 -6.374892 90)
			(size 0.519938 1.4986)
			(layers "F.Cu" "F.Mask" "F.Paste")
			(net "GND")
		)
		(pad "213" smd rect
			(at 2.050034 -5.525008 90)
			(size 0.519938 1.4986)
			(layers "F.Cu" "F.Mask" "F.Paste")
			(net "M_K_CPU0_SA_CA<3>")
		)
		(pad "214" smd rect
			(at 2.050034 -4.675124 90)
			(size 0.519938 1.4986)
			(layers "F.Cu" "F.Mask" "F.Paste")
			(net "GND")
		)
		(pad "215" smd rect
			(at 2.050034 -3.824986 90)
			(size 0.519938 1.4986)
			(layers "F.Cu" "F.Mask" "F.Paste")
			(net "M_K_CPU0_SA_CA<5>")
		)
		(pad "216" smd rect
			(at 2.050034 -2.975102 90)
			(size 0.519938 1.4986)
			(layers "F.Cu" "F.Mask" "F.Paste")
			(net "GND")
		)
		(pad "217" smd rect
			(at 2.050034 -2.124964 90)
			(size 0.519938 1.4986)
			(layers "F.Cu" "F.Mask" "F.Paste")
			(net "M_K_CPU0_CLK_DP<0>")
		)
		(pad "218" smd rect
			(at 2.050034 -1.27508 90)
			(size 0.519938 1.4986)
			(layers "F.Cu" "F.Mask" "F.Paste")
			(net "M_K_CPU0_CLK_DN<0>")
		)
		(pad "219" smd rect
			(at 2.050034 -0.424942 90)
			(size 0.519938 1.4986)
			(layers "F.Cu" "F.Mask" "F.Paste")
			(net "GND")
		)
		(pad "220" smd rect
			(at 2.050034 5.525008 90)
			(size 0.519938 1.4986)
			(layers "F.Cu" "F.Mask" "F.Paste")
			(net "Net_2393")
		)
		(pad "221" smd rect
			(at 2.050034 6.374892 90)
			(size 0.519938 1.4986)
			(layers "F.Cu" "F.Mask" "F.Paste")
			(net "M_K_CPU0_SB_CA<1>")
		)
		(pad "222" smd rect
			(at 2.050034 7.22503 90)
			(size 0.519938 1.4986)
			(layers "F.Cu" "F.Mask" "F.Paste")
			(net "GND")
		)
		(pad "223" smd rect
			(at 2.050034 8.074914 90)
			(size 0.519938 1.4986)
			(layers "F.Cu" "F.Mask" "F.Paste")
			(net "M_K_CPU0_SB_CA<3>")
		)
		(pad "224" smd rect
			(at 2.050034 8.925052 90)
			(size 0.519938 1.4986)
			(layers "F.Cu" "F.Mask" "F.Paste")
			(net "GND")
		)
		(pad "225" smd rect
			(at 2.050034 9.774936 90)
			(size 0.519938 1.4986)
			(layers "F.Cu" "F.Mask" "F.Paste")
			(net "M_K_CPU0_SB_CA<5>")
		)
		(pad "226" smd rect
			(at 2.050034 10.625074 90)
			(size 0.519938 1.4986)
			(layers "F.Cu" "F.Mask" "F.Paste")
			(net "GND")
		)
	)
)
